(kicad_pcb
	(version 20260206)
	(generator "pcbnew")
	(generator_version "10.0")
	(general
		(thickness 1.6)
		(legacy_teardrops no)
	)
	(paper "A4")
	(title_block
		(title "03242023_DA0F0TMBIJ0_F0T_Motherboard_J_brd_V01_OCP.brd")
		(comment 1 "Grand Teton / footprints 5511-5517 of 6105")
	)
	(layers
		(0 "F.Cu" signal "TOP")
		(4 "In1.Cu" signal "GND")
		(6 "In2.Cu" signal "IN1")
		(8 "In3.Cu" signal "GND1")
		(10 "In4.Cu" signal "IN2")
		(12 "In5.Cu" signal "GND2")
		(14 "In6.Cu" signal "IN3")
		(16 "In7.Cu" signal "GND3")
		(18 "In8.Cu" signal "VCC")
		(20 "In9.Cu" signal "VCC1")
		(22 "In10.Cu" signal "GND4")
		(24 "In11.Cu" signal "IN4")
		(26 "In12.Cu" signal "GND5")
		(28 "In13.Cu" signal "IN5")
		(30 "In14.Cu" signal "GND6")
		(32 "In15.Cu" signal "IN6")
		(34 "In16.Cu" signal "GND7")
		(2 "B.Cu" signal "BOTTOM")
		(9 "F.Adhes" user "F.Adhesive")
		(11 "B.Adhes" user "B.Adhesive")
		(13 "F.Paste" user "Package Geometry/Pastemask Top")
		(15 "B.Paste" user "Package Geometry/Pastemask Bottom")
		(5 "F.SilkS" user "Ref Des/Silkscreen Top")
		(7 "B.SilkS" user "Ref Des/Silkscreen Bottom")
		(1 "F.Mask" user "Board Geometry/Soldermask Top")
		(3 "B.Mask" user "Board Geometry/Soldermask Bottom")
		(17 "Dwgs.User" user "User.Drawings")
		(19 "Cmts.User" user "User.Comments")
		(21 "Eco1.User" user "User.Eco1")
		(23 "Eco2.User" user "User.Eco2")
		(25 "Edge.Cuts" user "Board Geometry/Outline")
		(27 "Margin" user)
		(31 "F.CrtYd" user "Package Geometry/Place Bound Top")
		(29 "B.CrtYd" user "Package Geometry/Place Bound Bottom")
		(35 "F.Fab" user "Ref Des/Assembly Top")
		(33 "B.Fab" user "Ref Des/Assembly Bottom")
	)
	(footprint ""
		(layer "B.Cu")
		(at 268.668246 -193.503296 -90)
		(property "Reference" "C623"
			(at 0 0 90)
			(layer "B.SilkS")
			(hide yes)
			(effects
				(font
					(size 1.27 1.27)
				)
				(justify mirror)
			)
		)
		(property "Value" ""
			(at 0 0 90)
			(layer "B.Fab")
			(effects
				(font
					(size 1.27 1.27)
				)
				(justify mirror)
			)
		)
		(duplicate_pad_numbers_are_jumpers no)
		(fp_line
			(start -0.7874 0.4064)
			(end 0.7874 0.4064)
			(stroke
				(width 0.1524)
				(type default)
			)
			(layer "B.SilkS")
		)
		(fp_line
			(start 0.7874 0.4064)
			(end 0.7874 -0.4064)
			(stroke
				(width 0.1524)
				(type default)
			)
			(layer "B.SilkS")
		)
		(fp_line
			(start -0.7874 -0.4064)
			(end -0.7874 0.4064)
			(stroke
				(width 0.1524)
				(type default)
			)
			(layer "B.SilkS")
		)
		(fp_line
			(start 0.7874 -0.4064)
			(end -0.7874 -0.4064)
			(stroke
				(width 0.1524)
				(type default)
			)
			(layer "B.SilkS")
		)
		(fp_line
			(start -0.67945 0.3048)
			(end -0.120396 0.3048)
			(stroke
				(width 0.1)
				(type default)
			)
			(layer "B.Fab")
		)
		(fp_line
			(start -0.120396 0.3048)
			(end -0.120396 0.2794)
			(stroke
				(width 0.1)
				(type default)
			)
			(layer "B.Fab")
		)
		(fp_line
			(start 0.12065 0.3048)
			(end 0.67945 0.3048)
			(stroke
				(width 0.1)
				(type default)
			)
			(layer "B.Fab")
		)
		(fp_line
			(start 0.67945 0.3048)
			(end 0.67945 -0.305054)
			(stroke
				(width 0.1)
				(type default)
			)
			(layer "B.Fab")
		)
		(fp_line
			(start -0.120396 0.2794)
			(end 0.12065 0.2794)
			(stroke
				(width 0.1)
				(type default)
			)
			(layer "B.Fab")
		)
		(fp_line
			(start 0.12065 0.2794)
			(end 0.12065 0.3048)
			(stroke
				(width 0.1)
				(type default)
			)
			(layer "B.Fab")
		)
		(fp_line
			(start -0.12065 -0.2794)
			(end -0.12065 -0.3048)
			(stroke
				(width 0.1)
				(type default)
			)
			(layer "B.Fab")
		)
		(fp_line
			(start 0.12065 -0.2794)
			(end -0.12065 -0.2794)
			(stroke
				(width 0.1)
				(type default)
			)
			(layer "B.Fab")
		)
		(fp_line
			(start -0.67945 -0.3048)
			(end -0.67945 0.3048)
			(stroke
				(width 0.1)
				(type default)
			)
			(layer "B.Fab")
		)
		(fp_line
			(start -0.12065 -0.3048)
			(end -0.67945 -0.3048)
			(stroke
				(width 0.1)
				(type default)
			)
			(layer "B.Fab")
		)
		(fp_line
			(start 0.12065 -0.305054)
			(end 0.12065 -0.2794)
			(stroke
				(width 0.1)
				(type default)
			)
			(layer "B.Fab")
		)
		(fp_line
			(start 0.67945 -0.305054)
			(end 0.12065 -0.305054)
			(stroke
				(width 0.1)
				(type default)
			)
			(layer "B.Fab")
		)
		(pad "1" smd circle
			(at 0.40005 0 90)
			(size 0 0)
			(layers "B.Cu" "B.Mask" "B.Paste")
			(net "RST_PLD_CPU0_DRAM_CD_N")
		)
		(pad "2" smd circle
			(at -0.40005 0 90)
			(size 0 0)
			(layers "B.Cu" "B.Mask" "B.Paste")
			(net "GND")
		)
	)
	(footprint ""
		(layer "B.Cu")
		(at 149.099524 -189.963298 180)
		(property "Reference" "R291"
			(at 0 0 0)
			(layer "B.SilkS")
			(hide yes)
			(effects
				(font
					(size 1.27 1.27)
				)
				(justify mirror)
			)
		)
		(property "Value" ""
			(at 0 0 0)
			(layer "B.Fab")
			(effects
				(font
					(size 1.27 1.27)
				)
				(justify mirror)
			)
		)
		(duplicate_pad_numbers_are_jumpers no)
		(fp_line
			(start 0.7874 0.4064)
			(end 0.7874 -0.4064)
			(stroke
				(width 0.1524)
				(type default)
			)
			(layer "B.SilkS")
		)
		(fp_line
			(start 0.7874 -0.4064)
			(end -0.7874 -0.4064)
			(stroke
				(width 0.1524)
				(type default)
			)
			(layer "B.SilkS")
		)
		(fp_line
			(start -0.7874 0.4064)
			(end 0.7874 0.4064)
			(stroke
				(width 0.1524)
				(type default)
			)
			(layer "B.SilkS")
		)
		(fp_line
			(start -0.7874 -0.4064)
			(end -0.7874 0.4064)
			(stroke
				(width 0.1524)
				(type default)
			)
			(layer "B.SilkS")
		)
		(fp_line
			(start 0.67945 0.3048)
			(end 0.67945 -0.305054)
			(stroke
				(width 0.1)
				(type default)
			)
			(layer "B.Fab")
		)
		(fp_line
			(start 0.67945 -0.305054)
			(end 0.12065 -0.305054)
			(stroke
				(width 0.1)
				(type default)
			)
			(layer "B.Fab")
		)
		(fp_line
			(start 0.12065 0.3048)
			(end 0.67945 0.3048)
			(stroke
				(width 0.1)
				(type default)
			)
			(layer "B.Fab")
		)
		(fp_line
			(start 0.12065 0.2794)
			(end 0.12065 0.3048)
			(stroke
				(width 0.1)
				(type default)
			)
			(layer "B.Fab")
		)
		(fp_line
			(start 0.12065 -0.2794)
			(end -0.12065 -0.2794)
			(stroke
				(width 0.1)
				(type default)
			)
			(layer "B.Fab")
		)
		(fp_line
			(start 0.12065 -0.305054)
			(end 0.12065 -0.2794)
			(stroke
				(width 0.1)
				(type default)
			)
			(layer "B.Fab")
		)
		(fp_line
			(start -0.120396 0.3048)
			(end -0.120396 0.2794)
			(stroke
				(width 0.1)
				(type default)
			)
			(layer "B.Fab")
		)
		(fp_line
			(start -0.120396 0.2794)
			(end 0.12065 0.2794)
			(stroke
				(width 0.1)
				(type default)
			)
			(layer "B.Fab")
		)
		(fp_line
			(start -0.12065 -0.2794)
			(end -0.12065 -0.3048)
			(stroke
				(width 0.1)
				(type default)
			)
			(layer "B.Fab")
		)
		(fp_line
			(start -0.12065 -0.3048)
			(end -0.67945 -0.3048)
			(stroke
				(width 0.1)
				(type default)
			)
			(layer "B.Fab")
		)
		(fp_line
			(start -0.67945 0.3048)
			(end -0.120396 0.3048)
			(stroke
				(width 0.1)
				(type default)
			)
			(layer "B.Fab")
		)
		(fp_line
			(start -0.67945 -0.3048)
			(end -0.67945 0.3048)
			(stroke
				(width 0.1)
				(type default)
			)
			(layer "B.Fab")
		)
		(pad "1" smd circle
			(at 0.40005 0)
			(size 0 0)
			(layers "B.Cu" "B.Mask" "B.Paste")
			(net "GND")
		)
		(pad "2" smd circle
			(at -0.40005 0)
			(size 0 0)
			(layers "B.Cu" "B.Mask" "B.Paste")
			(net "PD_CPU1_ENH_MCECC_DIS")
		)
	)
	(footprint ""
		(layer "B.Cu")
		(at 375.197116 -338.098892 -90)
		(property "Reference" "PR141"
			(at 0 0 90)
			(layer "B.SilkS")
			(hide yes)
			(effects
				(font
					(size 1.27 1.27)
				)
				(justify mirror)
			)
		)
		(property "Value" ""
			(at 0 0 90)
			(layer "B.Fab")
			(effects
				(font
					(size 1.27 1.27)
				)
				(justify mirror)
			)
		)
		(duplicate_pad_numbers_are_jumpers no)
		(fp_line
			(start -0.7874 0.4064)
			(end 0.7874 0.4064)
			(stroke
				(width 0.1524)
				(type default)
			)
			(layer "B.SilkS")
		)
		(fp_line
			(start 0.7874 0.4064)
			(end 0.7874 -0.4064)
			(stroke
				(width 0.1524)
				(type default)
			)
			(layer "B.SilkS")
		)
		(fp_line
			(start -0.7874 -0.4064)
			(end -0.7874 0.4064)
			(stroke
				(width 0.1524)
				(type default)
			)
			(layer "B.SilkS")
		)
		(fp_line
			(start 0.7874 -0.4064)
			(end -0.7874 -0.4064)
			(stroke
				(width 0.1524)
				(type default)
			)
			(layer "B.SilkS")
		)
		(fp_line
			(start -0.67945 0.3048)
			(end -0.120396 0.3048)
			(stroke
				(width 0.1)
				(type default)
			)
			(layer "B.Fab")
		)
		(fp_line
			(start -0.120396 0.3048)
			(end -0.120396 0.2794)
			(stroke
				(width 0.1)
				(type default)
			)
			(layer "B.Fab")
		)
		(fp_line
			(start 0.12065 0.3048)
			(end 0.67945 0.3048)
			(stroke
				(width 0.1)
				(type default)
			)
			(layer "B.Fab")
		)
		(fp_line
			(start 0.67945 0.3048)
			(end 0.67945 -0.305054)
			(stroke
				(width 0.1)
				(type default)
			)
			(layer "B.Fab")
		)
		(fp_line
			(start -0.120396 0.2794)
			(end 0.12065 0.2794)
			(stroke
				(width 0.1)
				(type default)
			)
			(layer "B.Fab")
		)
		(fp_line
			(start 0.12065 0.2794)
			(end 0.12065 0.3048)
			(stroke
				(width 0.1)
				(type default)
			)
			(layer "B.Fab")
		)
		(fp_line
			(start -0.12065 -0.2794)
			(end -0.12065 -0.3048)
			(stroke
				(width 0.1)
				(type default)
			)
			(layer "B.Fab")
		)
		(fp_line
			(start 0.12065 -0.2794)
			(end -0.12065 -0.2794)
			(stroke
				(width 0.1)
				(type default)
			)
			(layer "B.Fab")
		)
		(fp_line
			(start -0.67945 -0.3048)
			(end -0.67945 0.3048)
			(stroke
				(width 0.1)
				(type default)
			)
			(layer "B.Fab")
		)
		(fp_line
			(start -0.12065 -0.3048)
			(end -0.67945 -0.3048)
			(stroke
				(width 0.1)
				(type default)
			)
			(layer "B.Fab")
		)
		(fp_line
			(start 0.12065 -0.305054)
			(end 0.12065 -0.2794)
			(stroke
				(width 0.1)
				(type default)
			)
			(layer "B.Fab")
		)
		(fp_line
			(start 0.67945 -0.305054)
			(end 0.12065 -0.305054)
			(stroke
				(width 0.1)
				(type default)
			)
			(layer "B.Fab")
		)
		(pad "1" smd circle
			(at 0.40005 0 90)
			(size 0 0)
			(layers "B.Cu" "B.Mask" "B.Paste")
			(net "PVCCIN_CPU0_PVCC")
		)
		(pad "2" smd circle
			(at -0.40005 0 90)
			(size 0 0)
			(layers "B.Cu" "B.Mask" "B.Paste")
			(net "PVCCIN_CPU0_VDD5")
		)
	)
	(footprint ""
		(layer "B.Cu")
		(at 157.02788 -117.566948 180)
		(property "Reference" "R1757"
			(at 0 0 0)
			(layer "B.SilkS")
			(hide yes)
			(effects
				(font
					(size 1.27 1.27)
				)
				(justify mirror)
			)
		)
		(property "Value" ""
			(at 0 0 0)
			(layer "B.Fab")
			(effects
				(font
					(size 1.27 1.27)
				)
				(justify mirror)
			)
		)
		(duplicate_pad_numbers_are_jumpers no)
		(fp_line
			(start 0.7874 0.4064)
			(end 0.7874 -0.4064)
			(stroke
				(width 0.1524)
				(type default)
			)
			(layer "B.SilkS")
		)
		(fp_line
			(start 0.7874 -0.4064)
			(end -0.7874 -0.4064)
			(stroke
				(width 0.1524)
				(type default)
			)
			(layer "B.SilkS")
		)
		(fp_line
			(start -0.7874 0.4064)
			(end 0.7874 0.4064)
			(stroke
				(width 0.1524)
				(type default)
			)
			(layer "B.SilkS")
		)
		(fp_line
			(start -0.7874 -0.4064)
			(end -0.7874 0.4064)
			(stroke
				(width 0.1524)
				(type default)
			)
			(layer "B.SilkS")
		)
		(fp_line
			(start 0.67945 0.3048)
			(end 0.67945 -0.305054)
			(stroke
				(width 0.1)
				(type default)
			)
			(layer "B.Fab")
		)
		(fp_line
			(start 0.67945 -0.305054)
			(end 0.12065 -0.305054)
			(stroke
				(width 0.1)
				(type default)
			)
			(layer "B.Fab")
		)
		(fp_line
			(start 0.12065 0.3048)
			(end 0.67945 0.3048)
			(stroke
				(width 0.1)
				(type default)
			)
			(layer "B.Fab")
		)
		(fp_line
			(start 0.12065 0.2794)
			(end 0.12065 0.3048)
			(stroke
				(width 0.1)
				(type default)
			)
			(layer "B.Fab")
		)
		(fp_line
			(start 0.12065 -0.2794)
			(end -0.12065 -0.2794)
			(stroke
				(width 0.1)
				(type default)
			)
			(layer "B.Fab")
		)
		(fp_line
			(start 0.12065 -0.305054)
			(end 0.12065 -0.2794)
			(stroke
				(width 0.1)
				(type default)
			)
			(layer "B.Fab")
		)
		(fp_line
			(start -0.120396 0.3048)
			(end -0.120396 0.2794)
			(stroke
				(width 0.1)
				(type default)
			)
			(layer "B.Fab")
		)
		(fp_line
			(start -0.120396 0.2794)
			(end 0.12065 0.2794)
			(stroke
				(width 0.1)
				(type default)
			)
			(layer "B.Fab")
		)
		(fp_line
			(start -0.12065 -0.2794)
			(end -0.12065 -0.3048)
			(stroke
				(width 0.1)
				(type default)
			)
			(layer "B.Fab")
		)
		(fp_line
			(start -0.12065 -0.3048)
			(end -0.67945 -0.3048)
			(stroke
				(width 0.1)
				(type default)
			)
			(layer "B.Fab")
		)
		(fp_line
			(start -0.67945 0.3048)
			(end -0.120396 0.3048)
			(stroke
				(width 0.1)
				(type default)
			)
			(layer "B.Fab")
		)
		(fp_line
			(start -0.67945 -0.3048)
			(end -0.67945 0.3048)
			(stroke
				(width 0.1)
				(type default)
			)
			(layer "B.Fab")
		)
		(pad "1" smd circle
			(at 0.40005 0)
			(size 0 0)
			(layers "B.Cu" "B.Mask" "B.Paste")
			(net "SGPIO_DI_1")
		)
		(pad "2" smd circle
			(at -0.40005 0)
			(size 0 0)
			(layers "B.Cu" "B.Mask" "B.Paste")
			(net "SGPIO_BMC_DIN_R")
		)
	)
	(footprint ""
		(layer "B.Cu")
		(at 267.336016 -318.937894 90)
		(property "Reference" "R884"
			(at 0 0 90)
			(layer "B.SilkS")
			(hide yes)
			(effects
				(font
					(size 1.27 1.27)
				)
				(justify mirror)
			)
		)
		(property "Value" ""
			(at 0 0 90)
			(layer "B.Fab")
			(effects
				(font
					(size 1.27 1.27)
				)
				(justify mirror)
			)
		)
		(duplicate_pad_numbers_are_jumpers no)
		(fp_line
			(start 0.7874 -0.4064)
			(end -0.7874 -0.4064)
			(stroke
				(width 0.1524)
				(type default)
			)
			(layer "B.SilkS")
		)
		(fp_line
			(start -0.7874 -0.4064)
			(end -0.7874 0.4064)
			(stroke
				(width 0.1524)
				(type default)
			)
			(layer "B.SilkS")
		)
		(fp_line
			(start 0.7874 0.4064)
			(end 0.7874 -0.4064)
			(stroke
				(width 0.1524)
				(type default)
			)
			(layer "B.SilkS")
		)
		(fp_line
			(start -0.7874 0.4064)
			(end 0.7874 0.4064)
			(stroke
				(width 0.1524)
				(type default)
			)
			(layer "B.SilkS")
		)
		(fp_line
			(start 0.67945 -0.305054)
			(end 0.12065 -0.305054)
			(stroke
				(width 0.1)
				(type default)
			)
			(layer "B.Fab")
		)
		(fp_line
			(start 0.12065 -0.305054)
			(end 0.12065 -0.2794)
			(stroke
				(width 0.1)
				(type default)
			)
			(layer "B.Fab")
		)
		(fp_line
			(start -0.12065 -0.3048)
			(end -0.67945 -0.3048)
			(stroke
				(width 0.1)
				(type default)
			)
			(layer "B.Fab")
		)
		(fp_line
			(start -0.67945 -0.3048)
			(end -0.67945 0.3048)
			(stroke
				(width 0.1)
				(type default)
			)
			(layer "B.Fab")
		)
		(fp_line
			(start 0.12065 -0.2794)
			(end -0.12065 -0.2794)
			(stroke
				(width 0.1)
				(type default)
			)
			(layer "B.Fab")
		)
		(fp_line
			(start -0.12065 -0.2794)
			(end -0.12065 -0.3048)
			(stroke
				(width 0.1)
				(type default)
			)
			(layer "B.Fab")
		)
		(fp_line
			(start 0.12065 0.2794)
			(end 0.12065 0.3048)
			(stroke
				(width 0.1)
				(type default)
			)
			(layer "B.Fab")
		)
		(fp_line
			(start -0.120396 0.2794)
			(end 0.12065 0.2794)
			(stroke
				(width 0.1)
				(type default)
			)
			(layer "B.Fab")
		)
		(fp_line
			(start 0.67945 0.3048)
			(end 0.67945 -0.305054)
			(stroke
				(width 0.1)
				(type default)
			)
			(layer "B.Fab")
		)
		(fp_line
			(start 0.12065 0.3048)
			(end 0.67945 0.3048)
			(stroke
				(width 0.1)
				(type default)
			)
			(layer "B.Fab")
		)
		(fp_line
			(start -0.120396 0.3048)
			(end -0.120396 0.2794)
			(stroke
				(width 0.1)
				(type default)
			)
			(layer "B.Fab")
		)
		(fp_line
			(start -0.67945 0.3048)
			(end -0.120396 0.3048)
			(stroke
				(width 0.1)
				(type default)
			)
			(layer "B.Fab")
		)
		(pad "1" smd circle
			(at 0.40005 0 270)
			(size 0 0)
			(layers "B.Cu" "B.Mask" "B.Paste")
			(net "PWRGD_CHD_CPU0_DIMM2")
		)
		(pad "2" smd circle
			(at -0.40005 0 270)
			(size 0 0)
			(layers "B.Cu" "B.Mask" "B.Paste")
			(net "PWRGD_FAIL_CPU0_CD")
		)
	)
	(footprint ""
		(layer "B.Cu")
		(at 376.493532 -72.531224 180)
		(property "Reference" "PC1241"
			(at 0 0 0)
			(layer "B.SilkS")
			(hide yes)
			(effects
				(font
					(size 1.27 1.27)
				)
				(justify mirror)
			)
		)
		(property "Value" ""
			(at 0 0 0)
			(layer "B.Fab")
			(effects
				(font
					(size 1.27 1.27)
				)
				(justify mirror)
			)
		)
		(duplicate_pad_numbers_are_jumpers no)
		(fp_line
			(start 1.524 0.762)
			(end 1.524 -0.762)
			(stroke
				(width 0.1524)
				(type default)
			)
			(layer "B.SilkS")
		)
		(fp_line
			(start 1.524 -0.762)
			(end -1.524 -0.762)
			(stroke
				(width 0.1524)
				(type default)
			)
			(layer "B.SilkS")
		)
		(fp_line
			(start -1.524 0.762)
			(end 1.524 0.762)
			(stroke
				(width 0.1524)
				(type default)
			)
			(layer "B.SilkS")
		)
		(fp_line
			(start -1.524 -0.762)
			(end -1.524 0.762)
			(stroke
				(width 0.1524)
				(type default)
			)
			(layer "B.SilkS")
		)
		(fp_line
			(start 1.1049 0.724916)
			(end -1.1049 0.724916)
			(stroke
				(width 0.1)
				(type default)
			)
			(layer "B.Fab")
		)
		(fp_line
			(start 1.1049 -0.724916)
			(end 1.1049 0.724916)
			(stroke
				(width 0.1)
				(type default)
			)
			(layer "B.Fab")
		)
		(fp_line
			(start -1.1049 0.724916)
			(end -1.1049 -0.724916)
			(stroke
				(width 0.1)
				(type default)
			)
			(layer "B.Fab")
		)
		(fp_line
			(start -1.1049 -0.724916)
			(end 1.1049 -0.724916)
			(stroke
				(width 0.1)
				(type default)
			)
			(layer "B.Fab")
		)
		(pad "1" smd rect
			(at 0.889 0 180)
			(size 1.016 1.27)
			(layers "B.Cu" "B.Mask" "B.Paste")
			(net "P1V8_PCH_AUX")
		)
		(pad "2" smd rect
			(at -0.889 0 180)
			(size 1.016 1.27)
			(layers "B.Cu" "B.Mask" "B.Paste")
			(net "GND")
		)
	)
	(footprint ""
		(layer "B.Cu")
		(at 119.95912 -252.17628 -90)
		(property "Reference" "C353"
			(at 0 0 90)
			(layer "B.SilkS")
			(hide yes)
			(effects
				(font
					(size 1.27 1.27)
				)
				(justify mirror)
			)
		)
		(property "Value" ""
			(at 0 0 90)
			(layer "B.Fab")
			(effects
				(font
					(size 1.27 1.27)
				)
				(justify mirror)
			)
		)
		(duplicate_pad_numbers_are_jumpers no)
		(fp_line
			(start -1.524 0.762)
			(end 1.524 0.762)
			(stroke
				(width 0.1524)
				(type default)
			)
			(layer "B.SilkS")
		)
		(fp_line
			(start 1.524 0.762)
			(end 1.524 -0.762)
			(stroke
				(width 0.1524)
				(type default)
			)
			(layer "B.SilkS")
		)
		(fp_line
			(start -1.524 -0.762)
			(end -1.524 0.762)
			(stroke
				(width 0.1524)
				(type default)
			)
			(layer "B.SilkS")
		)
		(fp_line
			(start 1.524 -0.762)
			(end -1.524 -0.762)
			(stroke
				(width 0.1524)
				(type default)
			)
			(layer "B.SilkS")
		)
		(fp_line
			(start -1.1049 0.724916)
			(end -1.1049 -0.724916)
			(stroke
				(width 0.1)
				(type default)
			)
			(layer "B.Fab")
		)
		(fp_line
			(start 1.1049 0.724916)
			(end -1.1049 0.724916)
			(stroke
				(width 0.1)
				(type default)
			)
			(layer "B.Fab")
		)
		(fp_line
			(start -1.1049 -0.724916)
			(end 1.1049 -0.724916)
			(stroke
				(width 0.1)
				(type default)
			)
			(layer "B.Fab")
		)
		(fp_line
			(start 1.1049 -0.724916)
			(end 1.1049 0.724916)
			(stroke
				(width 0.1)
				(type default)
			)
			(layer "B.Fab")
		)
		(pad "1" smd rect
			(at 0.889 0 270)
			(size 1.016 1.27)
			(layers "B.Cu" "B.Mask" "B.Paste")
			(net "PVCCIN_CPU1")
		)
		(pad "2" smd rect
			(at -0.889 0 270)
			(size 1.016 1.27)
			(layers "B.Cu" "B.Mask" "B.Paste")
			(net "GND")
		)
	)
)
